(kicad_pcb
	(version 20240108)
	(generator "pcbnew")
	(generator_version "8.0")
	(general
		(thickness 1.62)
		(legacy_teardrops no)
	)
	(paper "A4")
	(title_block
		(title "Jetson Orin Baseboard")
		(date "2025-03-12")
		(rev "1.3.4")
		(company "Antmicro Ltd")
		(comment 1 "www.antmicro.com")
		(comment 9 "footprints 308-312 of 677")
	)
	(layers
		(0 "F.Cu" signal)
		(1 "In1.Cu" signal)
		(2 "In2.Cu" signal)
		(3 "In3.Cu" signal)
		(4 "In4.Cu" jumper)
		(5 "In5.Cu" signal)
		(6 "In6.Cu" signal)
		(31 "B.Cu" signal)
		(32 "B.Adhes" user "B.Adhesive")
		(33 "F.Adhes" user "F.Adhesive")
		(34 "B.Paste" user)
		(35 "F.Paste" user)
		(36 "B.SilkS" user "B.Silkscreen")
		(37 "F.SilkS" user "F.Silkscreen")
		(38 "B.Mask" user)
		(39 "F.Mask" user)
		(40 "Dwgs.User" user "User.Drawings")
		(41 "Cmts.User" user "User.Comments")
		(42 "Eco1.User" user "User.Eco1")
		(43 "Eco2.User" user "User.Eco2")
		(44 "Edge.Cuts" user)
		(45 "Margin" user)
		(46 "B.CrtYd" user "B.Courtyard")
		(47 "F.CrtYd" user "F.Courtyard")
		(48 "B.Fab" user)
		(49 "F.Fab" user)
	)
	(footprint "antmicro-footprints:R_0402_1005Metric"
		(layer "B.Cu")
		(at 108.9 104.4)
		(descr "Resistor SMD 0402")
		(tags "resistor SMD 0402")
		(property "Reference" "R266"
			(at -0.95 0.31 180)
			(layer "B.SilkS")
			(effects
				(font
					(size 0.7 0.7)
					(thickness 0.15)
				)
				(justify left bottom mirror)
			)
		)
		(property "Value" "R_200k_0402"
			(at 0 -1.4 180)
			(layer "B.Fab")
			(effects
				(font
					(size 0.7 0.7)
					(thickness 0.15)
				)
				(justify left bottom mirror)
			)
		)
		(property "Footprint" "antmicro-footprints:R_0402_1005Metric"
			(at 0 0 0)
			(layer "F.Fab")
			(hide yes)
			(effects
				(font
					(size 1.27 1.27)
					(thickness 0.15)
				)
			)
		)
		(property "Datasheet" "https://www.bourns.com/docs/product-datasheets/cr.pdf"
			(at 0 0 0)
			(layer "F.Fab")
			(hide yes)
			(effects
				(font
					(size 1.27 1.27)
					(thickness 0.15)
				)
			)
		)
		(property "Author" "Antmicro"
			(at 0 0 0)
			(layer "B.Fab")
			(hide yes)
			(effects
				(font
					(size 1 1)
					(thickness 0.15)
				)
				(justify mirror)
			)
		)
		(property "License" "Apache-2.0"
			(at 0 0 0)
			(layer "B.Fab")
			(hide yes)
			(effects
				(font
					(size 1 1)
					(thickness 0.15)
				)
				(justify mirror)
			)
		)
		(property "MPN" "CR0402-FX-2003GLF"
			(at 0 0 0)
			(layer "B.Fab")
			(hide yes)
			(effects
				(font
					(size 1 1)
					(thickness 0.15)
				)
				(justify mirror)
			)
		)
		(property "Manufacturer" "Bourns"
			(at 0 0 0)
			(layer "B.Fab")
			(hide yes)
			(effects
				(font
					(size 1 1)
					(thickness 0.15)
				)
				(justify mirror)
			)
		)
		(property "Tolerance" "1%"
			(at 0 0 0)
			(layer "B.Fab")
			(hide yes)
			(effects
				(font
					(size 1 1)
					(thickness 0.15)
				)
				(justify mirror)
			)
		)
		(property "Val" "200k"
			(at 0 0 0)
			(layer "B.Fab")
			(hide yes)
			(effects
				(font
					(size 1 1)
					(thickness 0.15)
				)
				(justify mirror)
			)
		)
		(sheetname "USB3")
		(sheetfile "usb3.kicad_sch")
		(attr smd)
		(fp_rect
			(start -0.925 0.47)
			(end 0.925 -0.47)
			(stroke
				(width 0.05)
				(type default)
			)
			(fill none)
			(layer "B.CrtYd")
		)
		(fp_rect
			(start -0.5 0.25)
			(end 0.5 -0.25)
			(stroke
				(width 0.15)
				(type solid)
			)
			(fill none)
			(layer "B.Fab")
		)
		(fp_text user "${REFERENCE}"
			(at -0.95 -3.168 180)
			(layer "B.Fab")
			(hide yes)
			(effects
				(font
					(size 0.7 0.7)
					(thickness 0.15)
				)
				(justify left bottom mirror)
			)
		)
		(fp_text user "License: Apache-2.0"
			(at -0.95 -5.169 180)
			(layer "B.Fab")
			(hide yes)
			(effects
				(font
					(size 0.7 0.7)
					(thickness 0.15)
				)
				(justify left bottom mirror)
			)
		)
		(fp_text user "Author: Antmicro"
			(at -0.95 -4.169 180)
			(layer "B.Fab")
			(hide yes)
			(effects
				(font
					(size 0.7 0.7)
					(thickness 0.15)
				)
				(justify left bottom mirror)
			)
		)
		(pad "1" smd roundrect
			(at -0.48 0)
			(size 0.59 0.64)
			(layers "B.Cu" "B.Paste" "B.Mask")
			(roundrect_rratio 0.25)
			(net 87 "+3V3")
			(pintype "passive")
		)
		(pad "2" smd roundrect
			(at 0.48 0)
			(size 0.59 0.64)
			(layers "B.Cu" "B.Paste" "B.Mask")
			(roundrect_rratio 0.25)
			(net 363 "/USB3/USBC1_ISC_SCL")
			(pintype "passive")
		)
	)
	(footprint "antmicro-footprints:C_0402_1005Metric"
		(layer "B.Cu")
		(at 65.55 108.1875 90)
		(descr "Capacitor SMD 0402")
		(tags "capacitor SMD 0402")
		(property "Reference" "C30"
			(at 1.1175 -0.35 -90)
			(layer "B.SilkS")
			(effects
				(font
					(size 0.7 0.7)
					(thickness 0.15)
				)
				(justify left bottom mirror)
			)
		)
		(property "Value" "C_10u_0402"
			(at -1.022927 -2.155213 -90)
			(layer "B.Fab")
			(effects
				(font
					(size 0.7 0.7)
					(thickness 0.15)
				)
				(justify left bottom mirror)
			)
		)
		(property "Footprint" "antmicro-footprints:C_0402_1005Metric"
			(at 0 0 90)
			(layer "F.Fab")
			(hide yes)
			(effects
				(font
					(size 1.27 1.27)
					(thickness 0.15)
				)
			)
		)
		(property "Datasheet" "https://www.yageo.com/en/Chart/Download/pdf/CC0402MRX5R5BB106"
			(at 0 0 90)
			(layer "F.Fab")
			(hide yes)
			(effects
				(font
					(size 1.27 1.27)
					(thickness 0.15)
				)
			)
		)
		(property "Author" "Antmicro"
			(at 173.7375 42.6375 0)
			(layer "B.Fab")
			(hide yes)
			(effects
				(font
					(size 1 1)
					(thickness 0.15)
				)
				(justify mirror)
			)
		)
		(property "Dielectric" ""
			(at 173.7375 42.6375 0)
			(layer "B.Fab")
			(hide yes)
			(effects
				(font
					(size 1 1)
					(thickness 0.15)
				)
				(justify mirror)
			)
		)
		(property "License" "Apache-2.0"
			(at 173.7375 42.6375 0)
			(layer "B.Fab")
			(hide yes)
			(effects
				(font
					(size 1 1)
					(thickness 0.15)
				)
				(justify mirror)
			)
		)
		(property "MPN" "CC0402MRX5R5BB106"
			(at 173.7375 42.6375 0)
			(layer "B.Fab")
			(hide yes)
			(effects
				(font
					(size 1 1)
					(thickness 0.15)
				)
				(justify mirror)
			)
		)
		(property "Manufacturer" "YAGEO"
			(at 173.7375 42.6375 0)
			(layer "B.Fab")
			(hide yes)
			(effects
				(font
					(size 1 1)
					(thickness 0.15)
				)
				(justify mirror)
			)
		)
		(property "Val" "10u"
			(at 173.7375 42.6375 0)
			(layer "B.Fab")
			(hide yes)
			(effects
				(font
					(size 1 1)
					(thickness 0.15)
				)
				(justify mirror)
			)
		)
		(property "Voltage" ""
			(at 173.7375 42.6375 0)
			(layer "B.Fab")
			(hide yes)
			(effects
				(font
					(size 1 1)
					(thickness 0.15)
				)
				(justify mirror)
			)
		)
		(sheetname "USB Debug, DP")
		(sheetfile "usb.kicad_sch")
		(attr smd)
		(fp_rect
			(start -0.925 0.47)
			(end 0.925 -0.47)
			(stroke
				(width 0.05)
				(type default)
			)
			(fill none)
			(layer "B.CrtYd")
		)
		(fp_line
			(start 0.504 -0.248)
			(end 0.504 0.25)
			(stroke
				(width 0.15)
				(type solid)
			)
			(layer "B.Fab")
		)
		(fp_line
			(start -0.494 -0.248)
			(end 0.504 -0.248)
			(stroke
				(width 0.15)
				(type solid)
			)
			(layer "B.Fab")
		)
		(fp_line
			(start 0.504 0.25)
			(end -0.494 0.25)
			(stroke
				(width 0.15)
				(type solid)
			)
			(layer "B.Fab")
		)
		(fp_line
			(start -0.494 0.25)
			(end -0.494 -0.248)
			(stroke
				(width 0.15)
				(type solid)
			)
			(layer "B.Fab")
		)
		(fp_text user "License: Apache-2.0"
			(at -0.939 -5.799 -90)
			(layer "B.Fab")
			(hide yes)
			(effects
				(font
					(size 0.7 0.7)
					(thickness 0.15)
				)
				(justify left bottom mirror)
			)
		)
		(fp_text user "Author: Antmicro"
			(at -0.939 -3.399 -90)
			(layer "B.Fab")
			(hide yes)
			(effects
				(font
					(size 0.7 0.7)
					(thickness 0.15)
				)
				(justify left bottom mirror)
			)
		)
		(fp_text user "${REFERENCE}"
			(at -0.939 -4.599 -90)
			(layer "B.Fab")
			(hide yes)
			(effects
				(font
					(size 0.7 0.7)
					(thickness 0.15)
				)
				(justify left bottom mirror)
			)
		)
		(pad "1" smd roundrect
			(at -0.48 0 90)
			(size 0.59 0.64)
			(layers "B.Cu" "B.Paste" "B.Mask")
			(roundrect_rratio 0.25)
			(net 1 "GND")
			(pintype "passive")
		)
		(pad "2" smd roundrect
			(at 0.48 0 90)
			(size 0.59 0.64)
			(layers "B.Cu" "B.Paste" "B.Mask")
			(roundrect_rratio 0.25)
			(net 134 "/USB Debug, DP/PDC_LDO_3V3")
			(pintype "passive")
		)
	)
	(footprint "antmicro-footprints:Oscillator_SMD_ECS_2520MV_2.5x2mm"
		(layer "B.Cu")
		(at 112.014 83.058 90)
		(descr "Miniature Crystal Clock Oscillator ECS 2520MV series")
		(tags "Crystal Clock Oscillator ECS 2520MV SMD")
		(property "Reference" "Y1"
			(at 0.308 -1.464 0)
			(layer "B.SilkS")
			(effects
				(font
					(size 0.7 0.7)
					(thickness 0.15)
				)
				(justify left bottom mirror)
			)
		)
		(property "Value" "Oscillator_32.768kHz_ECS_2520MV"
			(at 0 -2.499 -90)
			(layer "B.Fab")
			(effects
				(font
					(size 0.7 0.7)
					(thickness 0.15)
				)
				(justify left bottom mirror)
			)
		)
		(property "Footprint" "antmicro-footprints:Oscillator_SMD_ECS_2520MV_2.5x2mm"
			(at 0 0 90)
			(layer "F.Fab")
			(hide yes)
			(effects
				(font
					(size 1.27 1.27)
					(thickness 0.15)
				)
			)
		)
		(property "Datasheet" "https://ecsxtal.com/store/pdf/ECS-327MVATX.pdf"
			(at 0 0 90)
			(layer "F.Fab")
			(hide yes)
			(effects
				(font
					(size 1.27 1.27)
					(thickness 0.15)
				)
			)
		)
		(property "Author" "Antmicro"
			(at 195.072 -28.956 0)
			(layer "B.Fab")
			(hide yes)
			(effects
				(font
					(size 1 1)
					(thickness 0.15)
				)
				(justify mirror)
			)
		)
		(property "License" "Apache-2.0"
			(at 195.072 -28.956 0)
			(layer "B.Fab")
			(hide yes)
			(effects
				(font
					(size 1 1)
					(thickness 0.15)
				)
				(justify mirror)
			)
		)
		(property "MPN" "ECS-327MVATX-2-CN-TR3"
			(at 195.072 -28.956 0)
			(layer "B.Fab")
			(hide yes)
			(effects
				(font
					(size 1 1)
					(thickness 0.15)
				)
				(justify mirror)
			)
		)
		(property "Manufacturer" "ECS Inc. International"
			(at 195.072 -28.956 0)
			(layer "B.Fab")
			(hide yes)
			(effects
				(font
					(size 1 1)
					(thickness 0.15)
				)
				(justify mirror)
			)
		)
		(property "Val" "32.768 kHz"
			(at 195.072 -28.956 0)
			(layer "B.Fab")
			(hide yes)
			(effects
				(font
					(size 1 1)
					(thickness 0.15)
				)
				(justify mirror)
			)
		)
		(sheetname "M.2")
		(sheetfile "m-2.kicad_sch")
		(attr smd)
		(fp_line
			(start 0.17 -1.36)
			(end -0.172 -1.36)
			(stroke
				(width 0.15)
				(type solid)
			)
			(layer "B.SilkS")
		)
		(fp_line
			(start 1.11 0.32)
			(end 1.11 -0.32)
			(stroke
				(width 0.15)
				(type solid)
			)
			(layer "B.SilkS")
		)
		(fp_line
			(start -1.111 0.32)
			(end -1.111 -0.32)
			(stroke
				(width 0.15)
				(type solid)
			)
			(layer "B.SilkS")
		)
		(fp_line
			(start 0.17 1.361)
			(end -0.16 1.361)
			(stroke
				(width 0.15)
				(type solid)
			)
			(layer "B.SilkS")
		)
		(fp_circle
			(center -1.1 1.5)
			(end -1.049 1.5)
			(stroke
				(width 0.15)
				(type solid)
			)
			(fill solid)
			(layer "B.SilkS")
		)
		(fp_rect
			(start -1.25 1.5)
			(end 1.25 -1.5)
			(stroke
				(width 0.05)
				(type solid)
			)
			(fill none)
			(layer "B.CrtYd")
		)
		(fp_line
			(start -0.5 1.25)
			(end -1 0.75)
			(stroke
				(width 0.15)
				(type solid)
			)
			(layer "B.Fab")
		)
		(fp_rect
			(start 1 -1.249)
			(end -1 1.25)
			(stroke
				(width 0.15)
				(type solid)
			)
			(fill none)
			(layer "B.Fab")
		)
		(fp_text user "${REFERENCE}"
			(at -1.25 -3.9 -90)
			(layer "B.Fab")
			(hide yes)
			(effects
				(font
					(size 0.7 0.7)
					(thickness 0.15)
				)
				(justify left bottom mirror)
			)
		)
		(fp_text user "Author: Antmicro"
			(at -1.25 -5.102 -90)
			(layer "B.Fab")
			(hide yes)
			(effects
				(font
					(size 0.7 0.7)
					(thickness 0.15)
				)
				(justify left bottom mirror)
			)
		)
		(fp_text user "License: Apache-2.0"
			(at -1.25 -6.302 -90)
			(layer "B.Fab")
			(hide yes)
			(effects
				(font
					(size 0.7 0.7)
					(thickness 0.15)
				)
				(justify left bottom mirror)
			)
		)
		(pad "1" smd roundrect
			(at -0.725 0.927 90)
			(size 0.8 0.9)
			(layers "B.Cu" "B.Paste" "B.Mask")
			(roundrect_rratio 0.25)
			(net 87 "+3V3")
			(pinfunction "EN")
			(pintype "input")
		)
		(pad "2" smd roundrect
			(at -0.725 -0.925 90)
			(size 0.8 0.9)
			(layers "B.Cu" "B.Paste" "B.Mask")
			(roundrect_rratio 0.25)
			(net 1 "GND")
			(pinfunction "GND")
			(pintype "power_in")
		)
		(pad "3" smd roundrect
			(at 0.723 -0.925 90)
			(size 0.8 0.9)
			(layers "B.Cu" "B.Paste" "B.Mask")
			(roundrect_rratio 0.25)
			(net 456 "/M.2/32.7KHZ_OUT")
			(pinfunction "OUT")
			(pintype "output")
		)
		(pad "4" smd roundrect
			(at 0.723 0.927 90)
			(size 0.8 0.9)
			(layers "B.Cu" "B.Paste" "B.Mask")
			(roundrect_rratio 0.25)
			(net 87 "+3V3")
			(pinfunction "VDD")
			(pintype "power_in")
		)
	)
	(footprint "antmicro-footprints:R_0402_1005Metric"
		(layer "B.Cu")
		(at 108.15175 95.525 90)
		(descr "Resistor SMD 0402")
		(tags "resistor SMD 0402")
		(property "Reference" "R179"
			(at 1.425 1.29825 -90)
			(layer "B.SilkS")
			(effects
				(font
					(size 0.7 0.7)
					(thickness 0.15)
				)
				(justify left bottom mirror)
			)
		)
		(property "Value" "R_0R_0402"
			(at 0 -1.4 -90)
			(layer "B.Fab")
			(effects
				(font
					(size 0.7 0.7)
					(thickness 0.15)
				)
				(justify left bottom mirror)
			)
		)
		(property "Footprint" "antmicro-footprints:R_0402_1005Metric"
			(at 0 0 90)
			(layer "F.Fab")
			(hide yes)
			(effects
				(font
					(size 1.27 1.27)
					(thickness 0.15)
				)
			)
		)
		(property "Datasheet" "https://industrial.panasonic.com/cdbs/www-data/pdf/RDA0000/AOA0000C301.pdf"
			(at 0 0 90)
			(layer "F.Fab")
			(hide yes)
			(effects
				(font
					(size 1.27 1.27)
					(thickness 0.15)
				)
			)
		)
		(property "Author" "Antmicro"
			(at 203.67675 -12.62675 0)
			(layer "B.Fab")
			(hide yes)
			(effects
				(font
					(size 1 1)
					(thickness 0.15)
				)
				(justify mirror)
			)
		)
		(property "Current" "1A"
			(at 203.67675 -12.62675 0)
			(layer "B.Fab")
			(hide yes)
			(effects
				(font
					(size 1 1)
					(thickness 0.15)
				)
				(justify mirror)
			)
		)
		(property "License" "Apache-2.0"
			(at 203.67675 -12.62675 0)
			(layer "B.Fab")
			(hide yes)
			(effects
				(font
					(size 1 1)
					(thickness 0.15)
				)
				(justify mirror)
			)
		)
		(property "MPN" "ERJ2GE0R00X"
			(at 203.67675 -12.62675 0)
			(layer "B.Fab")
			(hide yes)
			(effects
				(font
					(size 1 1)
					(thickness 0.15)
				)
				(justify mirror)
			)
		)
		(property "Manufacturer" "Panasonic"
			(at 203.67675 -12.62675 0)
			(layer "B.Fab")
			(hide yes)
			(effects
				(font
					(size 1 1)
					(thickness 0.15)
				)
				(justify mirror)
			)
		)
		(property "Tolerance" ""
			(at 203.67675 -12.62675 0)
			(layer "B.Fab")
			(hide yes)
			(effects
				(font
					(size 1 1)
					(thickness 0.15)
				)
				(justify mirror)
			)
		)
		(property "Val" "0R"
			(at 203.67675 -12.62675 0)
			(layer "B.Fab")
			(hide yes)
			(effects
				(font
					(size 1 1)
					(thickness 0.15)
				)
				(justify mirror)
			)
		)
		(sheetname "CSI")
		(sheetfile "csi.kicad_sch")
		(attr smd exclude_from_pos_files exclude_from_bom dnp)
		(fp_rect
			(start -0.925 0.47)
			(end 0.925 -0.47)
			(stroke
				(width 0.05)
				(type default)
			)
			(fill none)
			(layer "B.CrtYd")
		)
		(fp_rect
			(start -0.5 0.25)
			(end 0.5 -0.25)
			(stroke
				(width 0.15)
				(type solid)
			)
			(fill none)
			(layer "B.Fab")
		)
		(fp_text user "${REFERENCE}"
			(at -0.95 -3.168 -90)
			(layer "B.Fab")
			(hide yes)
			(effects
				(font
					(size 0.7 0.7)
					(thickness 0.15)
				)
				(justify left bottom mirror)
			)
		)
		(fp_text user "Author: Antmicro"
			(at -0.95 -4.169 -90)
			(layer "B.Fab")
			(hide yes)
			(effects
				(font
					(size 0.7 0.7)
					(thickness 0.15)
				)
				(justify left bottom mirror)
			)
		)
		(fp_text user "License: Apache-2.0"
			(at -0.95 -5.169 -90)
			(layer "B.Fab")
			(hide yes)
			(effects
				(font
					(size 0.7 0.7)
					(thickness 0.15)
				)
				(justify left bottom mirror)
			)
		)
		(pad "1" smd roundrect
			(at -0.48 0 90)
			(size 0.59 0.64)
			(layers "B.Cu" "B.Paste" "B.Mask")
			(roundrect_rratio 0.25)
			(net 636 "/CSI/CSIB_I2C_VCC")
			(pintype "passive")
		)
		(pad "2" smd roundrect
			(at 0.48 0 90)
			(size 0.59 0.64)
			(layers "B.Cu" "B.Paste" "B.Mask")
			(roundrect_rratio 0.25)
			(net 112 "+1V8")
			(pintype "passive")
		)
	)
	(footprint "antmicro-footprints:C_0402_1005Metric"
		(layer "B.Cu")
		(at 62.03 84.36 90)
		(descr "Capacitor SMD 0402")
		(tags "capacitor SMD 0402")
		(property "Reference" "C142"
			(at -3.76 0.48 90)
			(layer "B.SilkS")
			(effects
				(font
					(size 0.7 0.7)
					(thickness 0.15)
				)
				(justify right bottom mirror)
			)
		)
		(property "Value" "C_1u_0402"
			(at 0 -1.4 90)
			(layer "B.Fab")
			(effects
				(font
					(size 0.7 0.7)
					(thickness 0.15)
				)
				(justify right bottom mirror)
			)
		)
		(property "Footprint" "antmicro-footprints:C_0402_1005Metric"
			(at 0 0 90)
			(layer "F.Fab")
			(hide yes)
			(effects
				(font
					(size 1.27 1.27)
					(thickness 0.15)
				)
			)
		)
		(property "Datasheet" "https://product.tdk.com/en/search/capacitor/ceramic/mlcc/info?part_no=C1005X6S1A105K050BC"
			(at 0 0 90)
			(layer "F.Fab")
			(hide yes)
			(effects
				(font
					(size 1.27 1.27)
					(thickness 0.15)
				)
			)
		)
		(property "Author" "Antmicro"
			(at 146.39 22.33 0)
			(layer "B.Fab")
			(hide yes)
			(effects
				(font
					(size 1 1)
					(thickness 0.15)
				)
				(justify mirror)
			)
		)
		(property "Dielectric" ""
			(at 146.39 22.33 0)
			(layer "B.Fab")
			(hide yes)
			(effects
				(font
					(size 1 1)
					(thickness 0.15)
				)
				(justify mirror)
			)
		)
		(property "License" "Apache-2.0"
			(at 146.39 22.33 0)
			(layer "B.Fab")
			(hide yes)
			(effects
				(font
					(size 1 1)
					(thickness 0.15)
				)
				(justify mirror)
			)
		)
		(property "MPN" "C1005X6S1A105K050BC"
			(at 146.39 22.33 0)
			(layer "B.Fab")
			(hide yes)
			(effects
				(font
					(size 1 1)
					(thickness 0.15)
				)
				(justify mirror)
			)
		)
		(property "Manufacturer" "TDK"
			(at 146.39 22.33 0)
			(layer "B.Fab")
			(hide yes)
			(effects
				(font
					(size 1 1)
					(thickness 0.15)
				)
				(justify mirror)
			)
		)
		(property "Val" "1u"
			(at 146.39 22.33 0)
			(layer "B.Fab")
			(hide yes)
			(effects
				(font
					(size 1 1)
					(thickness 0.15)
				)
				(justify mirror)
			)
		)
		(property "Voltage" ""
			(at 146.39 22.33 0)
			(layer "B.Fab")
			(hide yes)
			(effects
				(font
					(size 1 1)
					(thickness 0.15)
				)
				(justify mirror)
			)
		)
		(sheetname "Supply")
		(sheetfile "supply.kicad_sch")
		(attr smd)
		(fp_rect
			(start -0.925 0.47)
			(end 0.925 -0.47)
			(stroke
				(width 0.05)
				(type default)
			)
			(fill none)
			(layer "B.CrtYd")
		)
		(fp_line
			(start 0.504 -0.248)
			(end 0.504 0.25)
			(stroke
				(width 0.15)
				(type solid)
			)
			(layer "B.Fab")
		)
		(fp_line
			(start -0.494 -0.248)
			(end 0.504 -0.248)
			(stroke
				(width 0.15)
				(type solid)
			)
			(layer "B.Fab")
		)
		(fp_line
			(start 0.504 0.25)
			(end -0.494 0.25)
			(stroke
				(width 0.15)
				(type solid)
			)
			(layer "B.Fab")
		)
		(fp_line
			(start -0.494 0.25)
			(end -0.494 -0.248)
			(stroke
				(width 0.15)
				(type solid)
			)
			(layer "B.Fab")
		)
		(fp_text user "Author: Antmicro"
			(at -0.932 -4.17 90)
			(layer "B.Fab")
			(hide yes)
			(effects
				(font
					(size 0.7 0.7)
					(thickness 0.15)
				)
				(justify right bottom mirror)
			)
		)
		(fp_text user "${REFERENCE}"
			(at -0.932 -3.168 90)
			(layer "B.Fab")
			(hide yes)
			(effects
				(font
					(size 0.7 0.7)
					(thickness 0.15)
				)
				(justify right bottom mirror)
			)
		)
		(fp_text user "License: Apache-2.0"
			(at -0.932 -5.17 90)
			(layer "B.Fab")
			(hide yes)
			(effects
				(font
					(size 0.7 0.7)
					(thickness 0.15)
				)
				(justify right bottom mirror)
			)
		)
		(pad "1" smd roundrect
			(at -0.48 0 90)
			(size 0.59 0.64)
			(layers "B.Cu" "B.Paste" "B.Mask")
			(roundrect_rratio 0.25)
			(net 1 "GND")
			(pintype "passive")
		)
		(pad "2" smd roundrect
			(at 0.48 0 90)
			(size 0.59 0.64)
			(layers "B.Cu" "B.Paste" "B.Mask")
			(roundrect_rratio 0.25)
			(net 139 "/Supply/1V8_LDO")
			(pintype "passive")
		)
	)
)
